# SCM (Grand Teton) — schematic netlist excerpt (pin names and nets, part order shuffled) for the footprints in the layout excerpt that follows; sources: Cadence DE-HDL packaged netlist, KiCad conversion of 12092022_DA0F0TMDCD0_F0T_Management_Board_D_brd_V3_OCP.brd

R590  Q_RES  33.2 1% CHIP  pkg 0402LF  page 12 : A = SMB_BMC_MM3_R_SDA ; B = SMB_BMC_MM3_SDA
R192  Q_RES  49.9 1% CHIP  pkg 0402LF  page 22 : A = PWRGD_P1V0_AUX_DELAY_BUF ; B = RST_BMC_SRST_BUF_R_N

(kicad_pcb
	(version 20260206)
	(generator "pcbnew")
	(generator_version "10.0")
	(general
		(thickness 1.6)
		(legacy_teardrops no)
	)
	(paper "A4")
	(title_block
		(title "12092022_DA0F0TMDCD0_F0T_Management_Board_D_brd_V3_OCP.brd")
		(comment 1 "Grand Teton / footprints 539-540 of 1440")
	)
	(layers
		(0 "F.Cu" signal "TOP")
		(4 "In1.Cu" signal "GND")
		(6 "In2.Cu" signal "IN1")
		(8 "In3.Cu" signal "GND1")
		(10 "In4.Cu" signal "IN2")
		(12 "In5.Cu" signal "VCC")
		(14 "In6.Cu" signal "VCC1")
		(16 "In7.Cu" signal "IN3")
		(18 "In8.Cu" signal "GND2")
		(20 "In9.Cu" signal "IN4")
		(22 "In10.Cu" signal "GND3")
		(2 "B.Cu" signal "BOTTOM")
		(9 "F.Adhes" user "F.Adhesive")
		(11 "B.Adhes" user "B.Adhesive")
		(13 "F.Paste" user "Package Geometry/Pastemask Top")
		(15 "B.Paste" user "Package Geometry/Pastemask Bottom")
		(5 "F.SilkS" user "Ref Des/Silkscreen Top")
		(7 "B.SilkS" user "Ref Des/Silkscreen Bottom")
		(1 "F.Mask" user "Board Geometry/Soldermask Top")
		(3 "B.Mask" user "Board Geometry/Soldermask Bottom")
		(17 "Dwgs.User" user "User.Drawings")
		(19 "Cmts.User" user "User.Comments")
		(21 "Eco1.User" user "User.Eco1")
		(23 "Eco2.User" user "User.Eco2")
		(25 "Edge.Cuts" user "Board Geometry/Outline")
		(27 "Margin" user)
		(31 "F.CrtYd" user "Package Geometry/Place Bound Top")
		(29 "B.CrtYd" user "Package Geometry/Place Bound Bottom")
		(35 "F.Fab" user "Ref Des/Assembly Top")
		(33 "B.Fab" user "Ref Des/Assembly Bottom")
	)
	(footprint ""
		(layer "F.Cu")
		(at 49.779682 -34.637726 -90)
		(property "Reference" "R590"
			(at 0 0 270)
			(layer "F.SilkS")
			(hide yes)
			(effects
				(font
					(size 1.27 1.27)
				)
			)
		)
		(property "Value" ""
			(at 0 0 270)
			(layer "F.Fab")
			(effects
				(font
					(size 1.27 1.27)
				)
			)
		)
		(duplicate_pad_numbers_are_jumpers no)
		(fp_line
			(start -0.7874 0.4064)
			(end -0.7874 -0.4064)
			(stroke
				(width 0.1524)
				(type default)
			)
			(layer "F.SilkS")
		)
		(fp_line
			(start 0.7874 0.4064)
			(end -0.7874 0.4064)
			(stroke
				(width 0.1524)
				(type default)
			)
			(layer "F.SilkS")
		)
		(fp_line
			(start -0.7874 -0.4064)
			(end 0.7874 -0.4064)
			(stroke
				(width 0.1524)
				(type default)
			)
			(layer "F.SilkS")
		)
		(fp_line
			(start 0.7874 -0.4064)
			(end 0.7874 0.4064)
			(stroke
				(width 0.1524)
				(type default)
			)
			(layer "F.SilkS")
		)
		(fp_line
			(start -0.67945 0.3048)
			(end -0.67945 -0.305054)
			(stroke
				(width 0.1)
				(type default)
			)
			(layer "F.Fab")
		)
		(fp_line
			(start -0.12065 0.3048)
			(end -0.67945 0.3048)
			(stroke
				(width 0.1)
				(type default)
			)
			(layer "F.Fab")
		)
		(fp_line
			(start 0.120396 0.3048)
			(end 0.120396 0.2794)
			(stroke
				(width 0.1)
				(type default)
			)
			(layer "F.Fab")
		)
		(fp_line
			(start 0.67945 0.3048)
			(end 0.120396 0.3048)
			(stroke
				(width 0.1)
				(type default)
			)
			(layer "F.Fab")
		)
		(fp_line
			(start -0.12065 0.2794)
			(end -0.12065 0.3048)
			(stroke
				(width 0.1)
				(type default)
			)
			(layer "F.Fab")
		)
		(fp_line
			(start 0.120396 0.2794)
			(end -0.12065 0.2794)
			(stroke
				(width 0.1)
				(type default)
			)
			(layer "F.Fab")
		)
		(fp_line
			(start -0.12065 -0.2794)
			(end 0.12065 -0.2794)
			(stroke
				(width 0.1)
				(type default)
			)
			(layer "F.Fab")
		)
		(fp_line
			(start 0.12065 -0.2794)
			(end 0.12065 -0.3048)
			(stroke
				(width 0.1)
				(type default)
			)
			(layer "F.Fab")
		)
		(fp_line
			(start 0.12065 -0.3048)
			(end 0.67945 -0.3048)
			(stroke
				(width 0.1)
				(type default)
			)
			(layer "F.Fab")
		)
		(fp_line
			(start 0.67945 -0.3048)
			(end 0.67945 0.3048)
			(stroke
				(width 0.1)
				(type default)
			)
			(layer "F.Fab")
		)
		(fp_line
			(start -0.67945 -0.305054)
			(end -0.12065 -0.305054)
			(stroke
				(width 0.1)
				(type default)
			)
			(layer "F.Fab")
		)
		(fp_line
			(start -0.12065 -0.305054)
			(end -0.12065 -0.2794)
			(stroke
				(width 0.1)
				(type default)
			)
			(layer "F.Fab")
		)
		(pad "1" smd circle
			(at -0.40005 0 270)
			(size 0 0)
			(layers "F.Cu" "F.Mask" "F.Paste")
			(net "SMB_BMC_MM3_R_SDA")
		)
		(pad "2" smd circle
			(at 0.40005 0 270)
			(size 0 0)
			(layers "F.Cu" "F.Mask" "F.Paste")
			(net "SMB_BMC_MM3_SDA")
		)
	)
	(footprint ""
		(layer "F.Cu")
		(at 10.033 -88.519)
		(property "Reference" "R192"
			(at 0 0 0)
			(layer "F.SilkS")
			(hide yes)
			(effects
				(font
					(size 1.27 1.27)
				)
			)
		)
		(property "Value" ""
			(at 0 0 0)
			(layer "F.Fab")
			(effects
				(font
					(size 1.27 1.27)
				)
			)
		)
		(duplicate_pad_numbers_are_jumpers no)
		(fp_line
			(start -0.7874 -0.4064)
			(end 0.7874 -0.4064)
			(stroke
				(width 0.1524)
				(type default)
			)
			(layer "F.SilkS")
		)
		(fp_line
			(start -0.7874 0.4064)
			(end -0.7874 -0.4064)
			(stroke
				(width 0.1524)
				(type default)
			)
			(layer "F.SilkS")
		)
		(fp_line
			(start 0.7874 -0.4064)
			(end 0.7874 0.4064)
			(stroke
				(width 0.1524)
				(type default)
			)
			(layer "F.SilkS")
		)
		(fp_line
			(start 0.7874 0.4064)
			(end -0.7874 0.4064)
			(stroke
				(width 0.1524)
				(type default)
			)
			(layer "F.SilkS")
		)
		(fp_line
			(start -0.67945 -0.305054)
			(end -0.12065 -0.305054)
			(stroke
				(width 0.1)
				(type default)
			)
			(layer "F.Fab")
		)
		(fp_line
			(start -0.67945 0.3048)
			(end -0.67945 -0.305054)
			(stroke
				(width 0.1)
				(type default)
			)
			(layer "F.Fab")
		)
		(fp_line
			(start -0.12065 -0.305054)
			(end -0.12065 -0.2794)
			(stroke
				(width 0.1)
				(type default)
			)
			(layer "F.Fab")
		)
		(fp_line
			(start -0.12065 -0.2794)
			(end 0.12065 -0.2794)
			(stroke
				(width 0.1)
				(type default)
			)
			(layer "F.Fab")
		)
		(fp_line
			(start -0.12065 0.2794)
			(end -0.12065 0.3048)
			(stroke
				(width 0.1)
				(type default)
			)
			(layer "F.Fab")
		)
		(fp_line
			(start -0.12065 0.3048)
			(end -0.67945 0.3048)
			(stroke
				(width 0.1)
				(type default)
			)
			(layer "F.Fab")
		)
		(fp_line
			(start 0.120396 0.2794)
			(end -0.12065 0.2794)
			(stroke
				(width 0.1)
				(type default)
			)
			(layer "F.Fab")
		)
		(fp_line
			(start 0.120396 0.3048)
			(end 0.120396 0.2794)
			(stroke
				(width 0.1)
				(type default)
			)
			(layer "F.Fab")
		)
		(fp_line
			(start 0.12065 -0.3048)
			(end 0.67945 -0.3048)
			(stroke
				(width 0.1)
				(type default)
			)
			(layer "F.Fab")
		)
		(fp_line
			(start 0.12065 -0.2794)
			(end 0.12065 -0.3048)
			(stroke
				(width 0.1)
				(type default)
			)
			(layer "F.Fab")
		)
		(fp_line
			(start 0.67945 -0.3048)
			(end 0.67945 0.3048)
			(stroke
				(width 0.1)
				(type default)
			)
			(layer "F.Fab")
		)
		(fp_line
			(start 0.67945 0.3048)
			(end 0.120396 0.3048)
			(stroke
				(width 0.1)
				(type default)
			)
			(layer "F.Fab")
		)
		(pad "1" smd circle
			(at -0.40005 0)
			(size 0 0)
			(layers "F.Cu" "F.Mask" "F.Paste")
			(net "PWRGD_P1V0_AUX_DELAY_BUF")
		)
		(pad "2" smd circle
			(at 0.40005 0)
			(size 0 0)
			(layers "F.Cu" "F.Mask" "F.Paste")
			(net "RST_BMC_SRST_BUF_R_N")
		)
	)
)
